# T6G (Grand Teton) — schematic netlist excerpt (pin names and nets, part order shuffled) for the footprints in the layout excerpt that follows; sources: Cadence DE-HDL packaged netlist, KiCad conversion of 04192023_DAF0TMB3IC0_F0TG_MB_C_brd_V02_OCP.brd

C7016  Q_CAP  100UF 4V 20% X6S  pkg C0805  page 301 : A = P0V9_CPU0_RT2_2A ; B = GND
C108  Q_CAP  0.1UF 25V 10% X7R  pkg 0402  page 91 : A = P3V3_AUX ; B = GND
R544  Q_RES  4.7K 5% CHIP  pkg 0402LF  page 55 : A = IRQ_CPU_BMC_NMI_N ; B = PVDD18_S5_P1

(kicad_pcb
	(version 20260206)
	(generator "pcbnew")
	(generator_version "10.0")
	(general
		(thickness 1.6)
		(legacy_teardrops no)
	)
	(paper "A4")
	(title_block
		(title "04192023_DAF0TMB3IC0_F0TG_MB_C_brd_V02_OCP.brd")
		(comment 1 "Grand Teton / footprints 5016-5018 of 8354")
	)
	(layers
		(0 "F.Cu" signal "TOP")
		(4 "In1.Cu" signal "GND")
		(6 "In2.Cu" signal "IN1")
		(8 "In3.Cu" signal "GND1")
		(10 "In4.Cu" signal "IN2")
		(12 "In5.Cu" signal "GND2")
		(14 "In6.Cu" signal "IN3")
		(16 "In7.Cu" signal "GND3")
		(18 "In8.Cu" signal "VCC")
		(20 "In9.Cu" signal "VCC1")
		(22 "In10.Cu" signal "GND4")
		(24 "In11.Cu" signal "IN4")
		(26 "In12.Cu" signal "GND5")
		(28 "In13.Cu" signal "IN5")
		(30 "In14.Cu" signal "GND6")
		(32 "In15.Cu" signal "IN6")
		(34 "In16.Cu" signal "GND7")
		(2 "B.Cu" signal "BOTTOM")
		(9 "F.Adhes" user "F.Adhesive")
		(11 "B.Adhes" user "B.Adhesive")
		(13 "F.Paste" user "Package Geometry/Pastemask Top")
		(15 "B.Paste" user "Package Geometry/Pastemask Bottom")
		(5 "F.SilkS" user "Ref Des/Silkscreen Top")
		(7 "B.SilkS" user "Ref Des/Silkscreen Bottom")
		(1 "F.Mask" user "Board Geometry/Soldermask Top")
		(3 "B.Mask" user "Board Geometry/Soldermask Bottom")
		(17 "Dwgs.User" user "User.Drawings")
		(19 "Cmts.User" user "User.Comments")
		(21 "Eco1.User" user "User.Eco1")
		(23 "Eco2.User" user "User.Eco2")
		(25 "Edge.Cuts" user "Board Geometry/Outline")
		(27 "Margin" user)
		(31 "F.CrtYd" user "Package Geometry/Place Bound Top")
		(29 "B.CrtYd" user "Package Geometry/Place Bound Bottom")
		(35 "F.Fab" user "Ref Des/Assembly Top")
		(33 "B.Fab" user "Ref Des/Assembly Bottom")
	)
	(footprint ""
		(layer "B.Cu")
		(at 94.470474 -302.805592)
		(property "Reference" "R544"
			(at 0 0 0)
			(layer "B.SilkS")
			(hide yes)
			(effects
				(font
					(size 1.27 1.27)
				)
				(justify mirror)
			)
		)
		(property "Value" ""
			(at 0 0 0)
			(layer "B.Fab")
			(effects
				(font
					(size 1.27 1.27)
				)
				(justify mirror)
			)
		)
		(duplicate_pad_numbers_are_jumpers no)
		(fp_line
			(start -0.7874 -0.4064)
			(end -0.7874 0.4064)
			(stroke
				(width 0.1524)
				(type default)
			)
			(layer "B.SilkS")
		)
		(fp_line
			(start -0.7874 0.4064)
			(end 0.7874 0.4064)
			(stroke
				(width 0.1524)
				(type default)
			)
			(layer "B.SilkS")
		)
		(fp_line
			(start 0.7874 -0.4064)
			(end -0.7874 -0.4064)
			(stroke
				(width 0.1524)
				(type default)
			)
			(layer "B.SilkS")
		)
		(fp_line
			(start 0.7874 0.4064)
			(end 0.7874 -0.4064)
			(stroke
				(width 0.1524)
				(type default)
			)
			(layer "B.SilkS")
		)
		(fp_line
			(start -0.67945 -0.3048)
			(end -0.67945 0.3048)
			(stroke
				(width 0.1)
				(type default)
			)
			(layer "B.Fab")
		)
		(fp_line
			(start -0.67945 0.3048)
			(end -0.120396 0.3048)
			(stroke
				(width 0.1)
				(type default)
			)
			(layer "B.Fab")
		)
		(fp_line
			(start -0.12065 -0.3048)
			(end -0.67945 -0.3048)
			(stroke
				(width 0.1)
				(type default)
			)
			(layer "B.Fab")
		)
		(fp_line
			(start -0.12065 -0.2794)
			(end -0.12065 -0.3048)
			(stroke
				(width 0.1)
				(type default)
			)
			(layer "B.Fab")
		)
		(fp_line
			(start -0.120396 0.2794)
			(end 0.12065 0.2794)
			(stroke
				(width 0.1)
				(type default)
			)
			(layer "B.Fab")
		)
		(fp_line
			(start -0.120396 0.3048)
			(end -0.120396 0.2794)
			(stroke
				(width 0.1)
				(type default)
			)
			(layer "B.Fab")
		)
		(fp_line
			(start 0.12065 -0.305054)
			(end 0.12065 -0.2794)
			(stroke
				(width 0.1)
				(type default)
			)
			(layer "B.Fab")
		)
		(fp_line
			(start 0.12065 -0.2794)
			(end -0.12065 -0.2794)
			(stroke
				(width 0.1)
				(type default)
			)
			(layer "B.Fab")
		)
		(fp_line
			(start 0.12065 0.2794)
			(end 0.12065 0.3048)
			(stroke
				(width 0.1)
				(type default)
			)
			(layer "B.Fab")
		)
		(fp_line
			(start 0.12065 0.3048)
			(end 0.67945 0.3048)
			(stroke
				(width 0.1)
				(type default)
			)
			(layer "B.Fab")
		)
		(fp_line
			(start 0.67945 -0.305054)
			(end 0.12065 -0.305054)
			(stroke
				(width 0.1)
				(type default)
			)
			(layer "B.Fab")
		)
		(fp_line
			(start 0.67945 0.3048)
			(end 0.67945 -0.305054)
			(stroke
				(width 0.1)
				(type default)
			)
			(layer "B.Fab")
		)
		(pad "1" smd circle
			(at 0.40005 0 180)
			(size 0 0)
			(layers "B.Cu" "B.Mask" "B.Paste")
			(net "IRQ_CPU_BMC_NMI_N")
		)
		(pad "2" smd circle
			(at -0.40005 0 180)
			(size 0 0)
			(layers "B.Cu" "B.Mask" "B.Paste")
			(net "PVDD18_S5_P1")
		)
	)
	(footprint ""
		(layer "B.Cu")
		(at 401.190968 -390.035034)
		(property "Reference" "C7016"
			(at 0 0 0)
			(layer "B.SilkS")
			(hide yes)
			(effects
				(font
					(size 1.27 1.27)
				)
				(justify mirror)
			)
		)
		(property "Value" ""
			(at 0 0 0)
			(layer "B.Fab")
			(effects
				(font
					(size 1.27 1.27)
				)
				(justify mirror)
			)
		)
		(duplicate_pad_numbers_are_jumpers no)
		(fp_line
			(start -1.524 -0.762)
			(end -1.524 0.762)
			(stroke
				(width 0.1524)
				(type default)
			)
			(layer "B.SilkS")
		)
		(fp_line
			(start -1.524 0.762)
			(end 1.524 0.762)
			(stroke
				(width 0.1524)
				(type default)
			)
			(layer "B.SilkS")
		)
		(fp_line
			(start 1.524 -0.762)
			(end -1.524 -0.762)
			(stroke
				(width 0.1524)
				(type default)
			)
			(layer "B.SilkS")
		)
		(fp_line
			(start 1.524 0.762)
			(end 1.524 -0.762)
			(stroke
				(width 0.1524)
				(type default)
			)
			(layer "B.SilkS")
		)
		(fp_line
			(start -1.1049 -0.724916)
			(end 1.1049 -0.724916)
			(stroke
				(width 0.1)
				(type default)
			)
			(layer "B.Fab")
		)
		(fp_line
			(start -1.1049 0.724916)
			(end -1.1049 -0.724916)
			(stroke
				(width 0.1)
				(type default)
			)
			(layer "B.Fab")
		)
		(fp_line
			(start 1.1049 -0.724916)
			(end 1.1049 0.724916)
			(stroke
				(width 0.1)
				(type default)
			)
			(layer "B.Fab")
		)
		(fp_line
			(start 1.1049 0.724916)
			(end -1.1049 0.724916)
			(stroke
				(width 0.1)
				(type default)
			)
			(layer "B.Fab")
		)
		(pad "1" smd rect
			(at 0.889 0)
			(size 1.016 1.27)
			(layers "B.Cu" "B.Mask" "B.Paste")
			(net "P0V9_CPU0_RT2_2A")
		)
		(pad "2" smd rect
			(at -0.889 0)
			(size 1.016 1.27)
			(layers "B.Cu" "B.Mask" "B.Paste")
			(net "GND")
		)
	)
	(footprint ""
		(layer "B.Cu")
		(at 268.892528 -193.99631)
		(property "Reference" "C108"
			(at 0 0 0)
			(layer "B.SilkS")
			(hide yes)
			(effects
				(font
					(size 1.27 1.27)
				)
				(justify mirror)
			)
		)
		(property "Value" ""
			(at 0 0 0)
			(layer "B.Fab")
			(effects
				(font
					(size 1.27 1.27)
				)
				(justify mirror)
			)
		)
		(duplicate_pad_numbers_are_jumpers no)
		(fp_line
			(start -0.7874 -0.4064)
			(end -0.7874 0.4064)
			(stroke
				(width 0.1524)
				(type default)
			)
			(layer "B.SilkS")
		)
		(fp_line
			(start -0.7874 0.4064)
			(end 0.7874 0.4064)
			(stroke
				(width 0.1524)
				(type default)
			)
			(layer "B.SilkS")
		)
		(fp_line
			(start 0.7874 -0.4064)
			(end -0.7874 -0.4064)
			(stroke
				(width 0.1524)
				(type default)
			)
			(layer "B.SilkS")
		)
		(fp_line
			(start 0.7874 0.4064)
			(end 0.7874 -0.4064)
			(stroke
				(width 0.1524)
				(type default)
			)
			(layer "B.SilkS")
		)
		(fp_line
			(start -0.67945 -0.3048)
			(end -0.67945 0.3048)
			(stroke
				(width 0.1)
				(type default)
			)
			(layer "B.Fab")
		)
		(fp_line
			(start -0.67945 0.3048)
			(end -0.120396 0.3048)
			(stroke
				(width 0.1)
				(type default)
			)
			(layer "B.Fab")
		)
		(fp_line
			(start -0.12065 -0.3048)
			(end -0.67945 -0.3048)
			(stroke
				(width 0.1)
				(type default)
			)
			(layer "B.Fab")
		)
		(fp_line
			(start -0.12065 -0.2794)
			(end -0.12065 -0.3048)
			(stroke
				(width 0.1)
				(type default)
			)
			(layer "B.Fab")
		)
		(fp_line
			(start -0.120396 0.2794)
			(end 0.12065 0.2794)
			(stroke
				(width 0.1)
				(type default)
			)
			(layer "B.Fab")
		)
		(fp_line
			(start -0.120396 0.3048)
			(end -0.120396 0.2794)
			(stroke
				(width 0.1)
				(type default)
			)
			(layer "B.Fab")
		)
		(fp_line
			(start 0.12065 -0.305054)
			(end 0.12065 -0.2794)
			(stroke
				(width 0.1)
				(type default)
			)
			(layer "B.Fab")
		)
		(fp_line
			(start 0.12065 -0.2794)
			(end -0.12065 -0.2794)
			(stroke
				(width 0.1)
				(type default)
			)
			(layer "B.Fab")
		)
		(fp_line
			(start 0.12065 0.2794)
			(end 0.12065 0.3048)
			(stroke
				(width 0.1)
				(type default)
			)
			(layer "B.Fab")
		)
		(fp_line
			(start 0.12065 0.3048)
			(end 0.67945 0.3048)
			(stroke
				(width 0.1)
				(type default)
			)
			(layer "B.Fab")
		)
		(fp_line
			(start 0.67945 -0.305054)
			(end 0.12065 -0.305054)
			(stroke
				(width 0.1)
				(type default)
			)
			(layer "B.Fab")
		)
		(fp_line
			(start 0.67945 0.3048)
			(end 0.67945 -0.305054)
			(stroke
				(width 0.1)
				(type default)
			)
			(layer "B.Fab")
		)
		(pad "1" smd circle
			(at 0.40005 0 180)
			(size 0 0)
			(layers "B.Cu" "B.Mask" "B.Paste")
			(net "P3V3_AUX")
		)
		(pad "2" smd circle
			(at -0.40005 0 180)
			(size 0 0)
			(layers "B.Cu" "B.Mask" "B.Paste")
			(net "GND")
		)
	)
)
